# T6G (Grand Teton) — schematic netlist excerpt (pin names and nets, part order shuffled) for the footprints in the layout excerpt that follows; sources: Cadence DE-HDL packaged netlist, KiCad conversion of 04192023_DAF0TMB3IC0_F0TG_MB_C_brd_V02_OCP.brd

PU4  ISL99390FRZTR5935  ISL99390FRZ-TR5935 IC  pkg QFN21_6X5XB  page 211
  VOS  = PVDDCR_CPU0_P1_VOS1
  AGND  = GND
  VCC  = PVDDCR_CPU0_P1_VCC1
  PVCC  = PVDDCR_CPU0_P1_PVCC
  PGND1  = GND
  GL1  = NC_PVDDCR_CPU0_P1_GL1_1
  PGND2  = GND
  SW  = SW_PVDDCR_CPU0_P1_SW1
  VIN1  = SW_P12V_AUX_PVDDCR_CPU0_P1_FLT
  VIN2  = SW_P12V_AUX_PVDDCR_CPU0_P1_FLT
  DNC  = NC_PVDDCR_CPU0_P1_DNC1
  PHASE  = SW_PVDDCR_CPU0_P1_PH1
  BOOT  = SW_PVDDCR_CPU0_P1_BOOT1
  PWM  = PVDDCR_CPU0_P1_PWM1
  EN  = PVDDCR_CPU0_P1_VCC1
  TOUT_FLT  = PVDDCR_CPU0_P1_TEMP0
  LSET  = PVDDCR_CPU0_P1_LSET1
  IOUT  = PVDDCR_CPU0_P1_IMON1
  REFIN  = PVDDCR_CPU0_P1_VCCS
  PGND3  = GND
  GL2  = NC_PVDDCR_CPU0_P1_GL2_1

(kicad_pcb
	(version 20260206)
	(generator "pcbnew")
	(generator_version "10.0")
	(general
		(thickness 1.6)
		(legacy_teardrops no)
	)
	(paper "A4")
	(title_block
		(title "04192023_DAF0TMB3IC0_F0TG_MB_C_brd_V02_OCP.brd")
		(comment 1 "Grand Teton / footprints 3100-3100 of 8354")
	)
	(layers
		(0 "F.Cu" signal "TOP")
		(4 "In1.Cu" signal "GND")
		(6 "In2.Cu" signal "IN1")
		(8 "In3.Cu" signal "GND1")
		(10 "In4.Cu" signal "IN2")
		(12 "In5.Cu" signal "GND2")
		(14 "In6.Cu" signal "IN3")
		(16 "In7.Cu" signal "GND3")
		(18 "In8.Cu" signal "VCC")
		(20 "In9.Cu" signal "VCC1")
		(22 "In10.Cu" signal "GND4")
		(24 "In11.Cu" signal "IN4")
		(26 "In12.Cu" signal "GND5")
		(28 "In13.Cu" signal "IN5")
		(30 "In14.Cu" signal "GND6")
		(32 "In15.Cu" signal "IN6")
		(34 "In16.Cu" signal "GND7")
		(2 "B.Cu" signal "BOTTOM")
		(9 "F.Adhes" user "F.Adhesive")
		(11 "B.Adhes" user "B.Adhesive")
		(13 "F.Paste" user "Package Geometry/Pastemask Top")
		(15 "B.Paste" user "Package Geometry/Pastemask Bottom")
		(5 "F.SilkS" user "Ref Des/Silkscreen Top")
		(7 "B.SilkS" user "Ref Des/Silkscreen Bottom")
		(1 "F.Mask" user "Board Geometry/Soldermask Top")
		(3 "B.Mask" user "Board Geometry/Soldermask Bottom")
		(17 "Dwgs.User" user "User.Drawings")
		(19 "Cmts.User" user "User.Comments")
		(21 "Eco1.User" user "User.Eco1")
		(23 "Eco2.User" user "User.Eco2")
		(25 "Edge.Cuts" user "Board Geometry/Outline")
		(27 "Margin" user)
		(31 "F.CrtYd" user "Package Geometry/Place Bound Top")
		(29 "B.CrtYd" user "Package Geometry/Place Bound Bottom")
		(35 "F.Fab" user "Ref Des/Assembly Top")
		(33 "B.Fab" user "Ref Des/Assembly Bottom")
	)
	(footprint ""
		(layer "F.Cu")
		(at 82.28457 -182.743856 180)
		(property "Reference" "PU4"
			(at -0.19812 -6.65861 0)
			(unlocked yes)
			(layer "F.SilkS")
			(effects
				(font
					(size 0.7874 0.5842)
					(thickness 0.1524)
				)
				(justify left)
			)
		)
		(property "Value" ""
			(at 0 0 180)
			(layer "F.Fab")
			(effects
				(font
					(size 1.27 1.27)
				)
			)
		)
		(duplicate_pad_numbers_are_jumpers no)
		(fp_line
			(start 2.500122 2.999994)
			(end 2.2987 2.999994)
			(stroke
				(width 0.1524)
				(type default)
			)
			(layer "F.SilkS")
		)
		(fp_line
			(start 2.500122 2.339594)
			(end 2.500122 2.999994)
			(stroke
				(width 0.1524)
				(type default)
			)
			(layer "F.SilkS")
		)
		(fp_line
			(start 2.500122 -2.999994)
			(end 2.500122 -2.44348)
			(stroke
				(width 0.1524)
				(type default)
			)
			(layer "F.SilkS")
		)
		(fp_line
			(start 2.31394 -2.999994)
			(end 2.500122 -2.999994)
			(stroke
				(width 0.1524)
				(type default)
			)
			(layer "F.SilkS")
		)
		(fp_line
			(start -2.2987 2.999994)
			(end -2.500122 2.999994)
			(stroke
				(width 0.1524)
				(type default)
			)
			(layer "F.SilkS")
		)
		(fp_line
			(start -2.500122 2.999994)
			(end -2.500122 2.339594)
			(stroke
				(width 0.1524)
				(type default)
			)
			(layer "F.SilkS")
		)
		(fp_line
			(start -2.500122 0.6604)
			(end -2.500122 0.229108)
			(stroke
				(width 0.1524)
				(type default)
			)
			(layer "F.SilkS")
		)
		(fp_line
			(start -2.500122 -2.529078)
			(end -2.500122 -2.999994)
			(stroke
				(width 0.1524)
				(type default)
			)
			(layer "F.SilkS")
		)
		(fp_line
			(start -2.500122 -2.999994)
			(end -2.24409 -2.999994)
			(stroke
				(width 0.1524)
				(type default)
			)
			(layer "F.SilkS")
		)
		(fp_poly
			(pts
				(xy -2.612898 -2.543556) (xy -3.380232 -2.799334) (xy -2.868676 -3.31089)
			)
			(stroke
				(width 0)
				(type default)
			)
			(fill yes)
			(layer "F.SilkS")
		)
		(fp_line
			(start 2.500122 2.999994)
			(end -2.500122 2.999994)
			(stroke
				(width 0.1)
				(type default)
			)
			(layer "F.Fab")
		)
		(fp_line
			(start 2.500122 -2.999994)
			(end 2.500122 2.999994)
			(stroke
				(width 0.1)
				(type default)
			)
			(layer "F.Fab")
		)
		(fp_line
			(start -2.500122 2.999994)
			(end -2.500122 -2.999994)
			(stroke
				(width 0.1)
				(type default)
			)
			(layer "F.Fab")
		)
		(fp_line
			(start -2.500122 -2.999994)
			(end 2.500122 -2.999994)
			(stroke
				(width 0.1)
				(type default)
			)
			(layer "F.Fab")
		)
		(fp_poly
			(pts
				(xy -4.218432 -2.783078) (xy -4.218432 -1.767078) (xy -3.202432 -2.275078)
			)
			(stroke
				(width 0)
				(type default)
			)
			(fill yes)
			(layer "F.Fab")
		)
		(pad "1" smd rect
			(at -2.400046 -2.275078 270)
			(size 0.2286 0.6096)
			(layers "F.Cu" "F.Mask" "F.Paste")
			(net "PVDDCR_CPU0_P1_VOS1")
		)
		(pad "2" smd rect
			(at -2.400046 -1.82499 270)
			(size 0.2286 0.6096)
			(layers "F.Cu" "F.Mask" "F.Paste")
			(net "GND")
		)
		(pad "3" smd rect
			(at -2.400046 -1.374902 270)
			(size 0.2286 0.6096)
			(layers "F.Cu" "F.Mask" "F.Paste")
			(net "PVDDCR_CPU0_P1_VCC1")
		)
		(pad "4" smd rect
			(at -2.400046 -0.925068 270)
			(size 0.2286 0.6096)
			(layers "F.Cu" "F.Mask" "F.Paste")
			(net "PVDDCR_CPU0_P1_PVCC")
		)
		(pad "5" smd rect
			(at -2.400046 -0.47498 270)
			(size 0.2286 0.6096)
			(layers "F.Cu" "F.Mask" "F.Paste")
			(net "GND")
		)
		(pad "6" smd rect
			(at -2.400046 -0.024892 270)
			(size 0.2286 0.6096)
			(layers "F.Cu" "F.Mask" "F.Paste")
			(net "NC_PVDDCR_CPU0_P1_GL1_1")
		)
		(pad "7_9-20_24" smd circle
			(at 0 1.150112 270)
			(size 0 0)
			(layers "F.Cu" "F.Mask" "F.Paste")
			(net "GND")
		)
		(pad "10_19" smd rect
			(at 0 2.899918 270)
			(size 0.6096 4.318)
			(layers "F.Cu" "F.Mask" "F.Paste")
			(net "SW_PVDDCR_CPU0_P1_SW1")
		)
		(pad "25_29" smd rect
			(at 1.549908 -1.279906 90)
			(size 2.0574 2.3114)
			(layers "F.Cu" "F.Mask" "F.Paste")
			(net "SW_P12V_AUX_PVDDCR_CPU0_P1_FLT")
		)
		(pad "30" smd rect
			(at 2.05994 -2.899918 180)
			(size 0.2286 0.6096)
			(layers "F.Cu" "F.Mask" "F.Paste")
			(net "SW_P12V_AUX_PVDDCR_CPU0_P1_FLT")
		)
		(pad "31" smd rect
			(at 1.610106 -2.899918 180)
			(size 0.2286 0.6096)
			(layers "F.Cu" "F.Mask" "F.Paste")
			(net "NC_PVDDCR_CPU0_P1_DNC1")
		)
		(pad "32" smd rect
			(at 1.160018 -2.899918 180)
			(size 0.2286 0.6096)
			(layers "F.Cu" "F.Mask" "F.Paste")
			(net "SW_PVDDCR_CPU0_P1_PH1")
		)
		(pad "33" smd rect
			(at 0.70993 -2.899918 180)
			(size 0.2286 0.6096)
			(layers "F.Cu" "F.Mask" "F.Paste")
			(net "SW_PVDDCR_CPU0_P1_BOOT1")
		)
		(pad "34" smd rect
			(at 0.260096 -2.899918 180)
			(size 0.2286 0.6096)
			(layers "F.Cu" "F.Mask" "F.Paste")
			(net "PVDDCR_CPU0_P1_PWM1")
		)
		(pad "35" smd rect
			(at -0.189992 -2.899918 180)
			(size 0.2286 0.6096)
			(layers "F.Cu" "F.Mask" "F.Paste")
			(net "PVDDCR_CPU0_P1_VCC1")
		)
		(pad "36" smd rect
			(at -0.64008 -2.899918 180)
			(size 0.2286 0.6096)
			(layers "F.Cu" "F.Mask" "F.Paste")
			(net "PVDDCR_CPU0_P1_TEMP0")
		)
		(pad "37" smd rect
			(at -1.089914 -2.899918 180)
			(size 0.2286 0.6096)
			(layers "F.Cu" "F.Mask" "F.Paste")
			(net "PVDDCR_CPU0_P1_LSET1")
		)
		(pad "38" smd rect
			(at -1.540002 -2.899918 180)
			(size 0.2286 0.6096)
			(layers "F.Cu" "F.Mask" "F.Paste")
			(net "PVDDCR_CPU0_P1_IMON1")
		)
		(pad "39" smd rect
			(at -1.99009 -2.899918 180)
			(size 0.2286 0.6096)
			(layers "F.Cu" "F.Mask" "F.Paste")
			(net "PVDDCR_CPU0_P1_VCCS")
		)
		(pad "40" smd rect
			(at -0.87503 -1.27508 180)
			(size 1.7526 1.9558)
			(layers "F.Cu" "F.Mask" "F.Paste")
			(net "GND")
		)
		(pad "41" smd rect
			(at -1.525016 0.249936 90)
			(size 0.3048 0.4572)
			(layers "F.Cu" "F.Mask" "F.Paste")
			(net "NC_PVDDCR_CPU0_P1_GL2_1")
		)
		(zone
			(layer "F.Cu")
			(hatch none 0.5)
			(connect_pads
				(clearance 0)
			)
			(min_thickness 0.25)
			(keepout
				(tracks not_allowed)
				(vias allowed)
				(pads allowed)
				(copperpour not_allowed)
				(footprints allowed)
			)
			(placement
				(enabled no)
				(sheetname "")
			)
			(fill
				(thermal_gap 0.5)
				(thermal_bridge_width 0.5)
				(island_removal_mode 0)
			)
			(polygon
				(pts
					(xy 84.784692 -185.288174) (xy 84.784692 -184.99455) (xy 79.784448 -184.99455) (xy 79.784448 -185.288174)
					(xy 80.07477 -185.288174) (xy 84.49437 -185.288174)
				)
			)
		)
		(zone
			(layer "F.Cu")
			(hatch none 0.5)
			(connect_pads
				(clearance 0)
			)
			(min_thickness 0.25)
			(keepout
				(tracks not_allowed)
				(vias allowed)
				(pads allowed)
				(copperpour not_allowed)
				(footprints allowed)
			)
			(placement
				(enabled no)
				(sheetname "")
			)
			(fill
				(thermal_gap 0.5)
				(thermal_bridge_width 0.5)
				(island_removal_mode 0)
			)
			(polygon
				(pts
					(xy 82.2325 -182.497476) (xy 82.2325 -180.440076) (xy 84.0867 -180.440076) (xy 84.0867 -180.681122)
					(xy 84.329016 -180.681122) (xy 84.329016 -180.199538) (xy 80.431386 -180.199538) (xy 80.431386 -180.38445)
					(xy 81.941162 -180.38445) (xy 81.941162 -182.54345) (xy 79.784448 -182.54345) (xy 79.784448 -182.793132)
					(xy 81.936844 -182.793132)
				)
			)
		)
	)
)
